FILE_TYPE = CONNECTIVITY;
{Allegro Design Entry HDL 17.2-2016 S081 (4005846) 1/11/2022}
"PAGE_NUMBER" = 248;
0"NC";
1"P3V3_AUX\g";
2"P12V_AUX\g";
3"P3V3_AUX\g";
4"P3V3_AUX\g";
5"P1V05_PCH_AUX\g";
6"P1V05_PCH_AUX\g";
7"GND\g";
8"GND\g";
9"GND\g";
10"GND\g";
11"GND\g";
12"GND\g";
13"GND\g";
14"GND\g";
15"GND\g";
16"GND\g";
17"GND\g";
18"PWRGD_PVNN_PCH_AUX";
19"PWRGD_P1V05_PCH_AUX";
20"PWRGD_P1V05_PCH_AUX_R";
21"SH_P1V05_PCH_AUX_P";
22"SH_P1V05_PCH_AUX_N";
23"P1V05_PCH_AUX_FB";
24"SW_P1V05_PCH_AUX_BST";
25"SW_P1V05_PCH_AUX_SW";
26"SW_P12V_AUX_P1V05_PCH_AUX_FLT";
27"FM_P1V05_PCH_AUX_R_EN"CDS_PHYS_NET_NAME"FM_P1V05_PCH_AUX_R_EN";
28"FM_P1V05_PCH_AUX_EN"CDS_PHYS_NET_NAME"FM_P1V05_PCH_AUX_EN";
29"P1V05_PCH_AUX_MODE";
30"P1V05_PCH_AUX_REF";
31"P1V05_PCH_AUX_VCC";
32"P1V05_PCH_AUX_CS";
%"UNIVERSAL_GND"
"1","(-3150,-1700)","0","logical_power","I1";
;
HDL_POWER"GND"
CDS_LIB"logical_power";
"A"7;
%"Q_RES"
"1","(-1625,-650)","0","pure_quanta","I10";
;
PART_NUMBER"CS00002JB13"
PACK_TYPE"0402LF"
VALUE"0"
TOLERANCE"5%"
MATERIAL"CHIP"
WATTAGE"1/16W"
LOCATION"PR338"
CDS_LIB"pure_quanta"
$SEC"1"
CDS_SEC"1";
"B"
$PN"2"10;
"A"
$PN"1"29;
%"RS53319LR"
"1","(-925,-525)","0","pure_quanta","I11";
;
PART_NUMBER"AL053319002"
PART_TYPE"SMLF"
VALUE"RS53319LR"
MATERIAL"IC"
LOCATION"PU73"
SEC_TYPE""
CDS_LIB"pure_quanta"
NEEDS_NO_SIZE"TRUE"
CDS_LMAN_SYM_OUTLINE"-250,725,250,-725"
SEC"1";
"VIN2"
$PN"21"26;
"CS"
$PN"3"32;
"MODE"
$PN"4"29;
"REF"
$PN"5"30;
"SW"
$PN"20"25;
"RTN"
$PN"6"22;
"VCC"
$PN"19"31;
"AGND"
$PN"2"11;
"FB"
$PN"7"23;
"BST"
$PN"1"24;
"EN"
$PN"8"27;
"PGND"
$PN"11_18"11;
"PGOOD"
$PN"9"20;
"VIN1"
$PN"10"26;
%"UNIVERSAL_GND"
"1","(-1375,-725)","0","logical_power","I12";
;
HDL_POWER"GND"
CDS_LIB"logical_power";
"A"10;
%"UNIVERSAL_GND"
"1","(-425,-1500)","0","logical_power","I13";
;
HDL_POWER"GND"
CDS_LIB"logical_power";
"A"11;
%"Q_CAP"
"1","(-275,-1275)","0","pure_quanta","I14";
;
PART_NUMBER"TMP_QCH32203KB11"
MATERIAL"X7R"
VOLTAGE"16V"
PACK_TYPE"0402"
TOLERANCE"10%"
VALUE"0.022UF"
LOCATION"PC2000"
CDS_LIB"pure_quanta"
$SEC"1"
CDS_SEC"1";
"B"
$PN"2"12;
"A"
$PN"1"30;
%"UNIVERSAL_GND"
"1","(-275,-1525)","0","logical_power","I15";
;
HDL_POWER"GND"
CDS_LIB"logical_power";
"A"12;
%"Q_CAP"
"1","(175,-1275)","0","pure_quanta","I16";
;
PART_NUMBER"CH4104K1B00"
VALUE"0.1UF"
MATERIAL"X7R"
VOLTAGE"25V"
PACK_TYPE"0402"
TOLERANCE"10%"
LOCATION"PC1221"
CDS_LIB"pure_quanta"
$SEC"1"
CDS_SEC"1";
"B"
$PN"2"22;
"A"
$PN"1"30;
%"GND"
"1","(-4900,175)","0","logical_power","I17";
;
HDL_POWER"GND"
SIZE"1B"
CDS_LIB"logical_power";
"A<SIZE-1..0>\NAC"13;
%"Q_CAP"
"1","(-4900,425)","0","pure_quanta","I18";
;
PART_NUMBER"CH4106K1B01"
MATERIAL"X7R"
PACK_TYPE"C0402"
VOLTAGE"50V"
TOLERANCE"10%"
VALUE"100NF"
LOCATION"PC1650"
CDS_LIB"pure_quanta"
$SEC"1"
CDS_SEC"1";
"B"
$PN"2"13;
"A"
$PN"1"2;
%"Q_INDUCTOR"
"1","(-4575,650)","0","pure_quanta","I19";
;
PART_NUMBER"CV+10G0MZ04"
PACK_TYPE"SMLF"
VALUE"100NH/16A"
MATERIAL"IND"
LOCATION"PL110"
CDS_LIB"pure_quanta"
NEEDS_NO_SIZE"TRUE"
$SEC"1"
CDS_SEC"1";
"1"
$PN"1"2;
"2"
$PN"2"26;
%"Q_CAP"
"1","(-3150,-1425)","0","pure_quanta","I2";
;
PART_NUMBER"CH5104KEB02"
PACK_TYPE"C0402"
VALUE"1UF"
TOLERANCE"10%"
VOLTAGE"25V"
MATERIAL"X6S"
LOCATION"PC113"
CDS_LIB"pure_quanta"
SEC_TYPE"C0402"
BOM_COST"VR_PCH"
SEC"1";
"B"
$PN"2"7;
"A"
$PN"1"31;
%"VCCAUX15"
"1","(-4900,1050)","0","logical_power","I20";
;
HDL_POWER"P12V_AUX"
CDS_LIB"logical_power"
BOM_COST"VR_PCH";
"A"2;
%"UNIVERSAL_GND"
"1","(-4325,50)","0","logical_power","I22";
;
HDL_POWER"GND"
CDS_LIB"logical_power";
"A"14;
%"Q_CAPP"
"1","(-4325,375)","0","pure_quanta","I23";
;
PART_NUMBER"CC71003MZ30"
TOLERANCE"20%"
MATERIAL"OSCON"
PACK_TYPE"SMLF"
VOLTAGE"16V"
VALUE"100UF"
$LOCATION"PC1215"
BOM_COST"VR_SYSTEM "
CDS_LIB"pure_quanta"
CDS_LOCATION"PC1215"
$SEC"1"
CDS_SEC"1";
"A"
$PN"1"26;
"B"
$PN"2"14;
%"VCCAUX15"
"1","(-3750,0)","0","logical_power","I24";
;
HDL_POWER"P3V3_AUX"
BOM_COST"VR_PCH"
CDS_LIB"logical_power";
"A"3;
%"Q_CAP"
"1","(-3725,375)","0","pure_quanta","I25";
;
PART_NUMBER"CH6223MEA01"
TOLERANCE"20%"
PACK_TYPE"C0805"
MATERIAL"X6S"
VOLTAGE"16V"
VALUE"22UF"
LOCATION"PC1216"
CDS_LIB"pure_quanta"
BOM_COST"VR_PCH"
$SEC"1"
CDS_SEC"1";
"B"
$PN"2"14;
"A"
$PN"1"26;
%"Q_RES"
"1","(-2950,-75)","0","pure_quanta","I26";
;
PART_NUMBER"CS31002FB08"
WATTAGE"1/16W"
MATERIAL"EMPTY"
TOLERANCE"1%"
PACK_TYPE"0402LF"
VALUE"10K"
LOCATION"PR1647"
CDS_LIB"pure_quanta"
$SEC"1"
CDS_SEC"1";
"B"
$PN"2"27;
"A"
$PN"1"3;
%"Q_RES"
"1","(-2950,-350)","0","pure_quanta","I27";
;
PART_NUMBER"CS00002JB13"
VALUE"0"
MATERIAL"CHIP"
TOLERANCE"5%"
LOCATION"R1389"
CDS_LIB"pure_quanta"
WATTAGE"1/16W"
PACK_TYPE"0402LF"
$SEC"1"
CDS_SEC"1";
"B"
$PN"2"27;
"A"
$PN"1"28;
%"Q_CAP"
"1","(-3275,375)","0","pure_quanta","I28";
;
PART_NUMBER"CH6223MEA01"
MATERIAL"X6S"
TOLERANCE"20%"
PACK_TYPE"C0805"
VALUE"22UF"
VOLTAGE"16V"
LOCATION"PC1217"
BOM_COST"VR_PCH"
CDS_LIB"pure_quanta"
$SEC"1"
CDS_SEC"1";
"B"
$PN"2"14;
"A"
$PN"1"26;
%"Q_CAP"
"1","(-2850,375)","0","pure_quanta","I29";
;
PART_NUMBER"CH6223MEA01"
MATERIAL"X6S"
TOLERANCE"20%"
VALUE"22UF"
VOLTAGE"16V"
PACK_TYPE"C0805"
LOCATION"PC1218"
BOM_COST"VR_PCH"
CDS_LIB"pure_quanta"
$SEC"1"
CDS_SEC"1";
"B"
$PN"2"14;
"A"
$PN"1"26;
%"Q_RES"
"2","(-3150,-1000)","0","pure_quanta","I3";
;
PART_NUMBER"CS00002JB13"
VALUE"0"
MATERIAL"CHIP"
PACK_TYPE"0402LF"
TOLERANCE"5%"
WATTAGE"1/16W"
LOCATION"PR1326"
CDS_LIB"pure_quanta"
$SEC"1"
CDS_SEC"1";
"A"
$PN"1"1;
"B"
$PN"2"31;
%"Q_CAP"
"1","(-2425,375)","0","pure_quanta","I30";
;
PART_NUMBER"CH5103KEB01"
PACK_TYPE"C0402"
TOLERANCE"10%"
MATERIAL"X6S"
VOLTAGE"16V"
VALUE"1UF"
LOCATION"PC1219"
CDS_LIB"pure_quanta"
$SEC"1"
CDS_SEC"1";
"B"
$PN"2"14;
"A"
$PN"1"26;
%"Q_CAP"
"1","(350,-125)","0","pure_quanta","I31";
;
PART_NUMBER"CH4224K1B01"
PACK_TYPE"C0402"
VOLTAGE"25V"
VALUE"0.22UF"
MATERIAL"X7R"
TOLERANCE"10%"
LOCATION"PC1222"
CDS_LIB"pure_quanta"
$SEC"1"
CDS_SEC"1";
"B"
$PN"2"25;
"A"
$PN"1"24;
%"Q_RES"
"2","(450,525)","0","pure_quanta","I32";
;
PART_NUMBER"CS31002FB08"
MATERIAL"CHIP"
WATTAGE"1/16W"
TOLERANCE"1%"
VALUE"10K"
PACK_TYPE"0402LF"
LOCATION"R2357"
CDS_LIB"pure_quanta"
BOM_COST"VR_PCH"
$SEC"1"
CDS_SEC"1";
"A"
$PN"1"4;
"B"
$PN"2"20;
%"UNIVERSAL_POWER"
"1","(450,775)","0","logical_power","I33";
;
HDL_POWER"P3V3_AUX"
CDS_LIB"logical_power";
"A"4;
%"Q_RES"
"2","(700,-1300)","0","pure_quanta","I34";
;
PART_NUMBER"CS31002BB06"
WATTAGE"1/16W"
VALUE"10K"
PACK_TYPE"0402LF"
MATERIAL"CHIP"
TOLERANCE"0.1%"
LOCATION"PR187"
CDS_LIB"pure_quanta"
BOM_COST"VR_PCH"
$SEC"1"
CDS_SEC"1";
"A"
$PN"1"23;
"B"
$PN"2"22;
%"Q_CAP"
"2","(1650,-1275)","0","pure_quanta","I35";
;
PART_NUMBER"TMP_QCH16806KB17"
VOLTAGE"50V"
PACK_TYPE"0402"
TOLERANCE"10%"
VALUE"680PF"
MATERIAL"X7R"
LOCATION"PC1223"
CDS_LIB"pure_quanta"
$SEC"1"
CDS_SEC"1";
"A"
$PN"1"23;
"B"
$PN"2"21;
%"Q_RES"
"1","(1650,-1050)","0","pure_quanta","I36";
;
PART_NUMBER"CS27322BB09"
MATERIAL"CHIP"
TOLERANCE"0.1%"
VALUE"7.32K"
PACK_TYPE"0402LF"
WATTAGE"1/16W"
LOCATION"PR1328"
CDS_LIB"pure_quanta"
$SEC"1"
CDS_SEC"1";
"B"
$PN"2"21;
"A"
$PN"1"23;
%"Q_CAP"
"1","(2325,-1250)","0","pure_quanta","I37";
;
PART_NUMBER"TMP_QCH31004KB17"
TOLERANCE"10%"
PACK_TYPE"0402"
VOLTAGE"25V"
MATERIAL"X7R"
VALUE"0.01UF"
LOCATION"PC2279"
CDS_LIB"pure_quanta"
$SEC"1"
CDS_SEC"1";
"B"
$PN"2"22;
"A"
$PN"1"21;
%"Q_CAP"
"1","(2225,-550)","0","pure_quanta","I38";
;
PART_NUMBER"CH4104K1B00"
MATERIAL"X7R"
VOLTAGE"25V"
VALUE"0.1UF"
PACK_TYPE"0402"
TOLERANCE"10%"
LOCATION"PC1224"
CDS_LIB"pure_quanta"
$SEC"1"
CDS_SEC"1";
"B"
$PN"2"16;
"A"
$PN"1"6;
%"UNIVERSAL_GND"
"1","(3675,-2850)","0","logical_power","I39";
;
HDL_POWER"GND"
CDS_LIB"logical_power";
"A"15;
%"UNIVERSAL_POWER"
"1","(-3150,-775)","0","logical_power","I4";
;
HDL_POWER"P3V3_AUX"
CDS_LIB"logical_power";
"A"1;
%"Q_CAPP"
"1","(2875,-2500)","0","pure_quanta","I40";
;
PART_NUMBER"CH733RY8807"
VOLTAGE"2V"
MATERIAL"SPCAP"
PACK_TYPE"SMLF"
TOLERANCE"35%"
VALUE"330UF"
LOCATION"PC117"
CDS_LIB"pure_quanta"
$SEC"1"
CDS_SEC"1";
"A"
$PN"1"5;
"B"
$PN"2"15;
%"Q_CAPP"
"1","(3275,-2500)","0","pure_quanta","I41";
;
PART_NUMBER"CC7560JMD16"
PACK_TYPE"THLF"
VALUE"560UF"
TOLERANCE"20%"
VOLTAGE"2.5V"
OSCON"OSCON"
LOCATION"PC1227"
MATERIAL"OSCON"
BOM_COST"VR_PCH"
CDS_LIB"pure_quanta"
$SEC"1"
CDS_SEC"1";
"A"
$PN"1"5;
"B"
$PN"2"15;
%"Q_SHORT"
"1","(3000,-1525)","0","pure_quanta","I42";
;
PART_NUMBER"SHORT6"
PACK_TYPE"SM"
MATERIAL"EMPTY"
LOCATION"PJ63"
CDS_LIB"pure_quanta"
BOM_COST"VR_PCH"
NEEDS_NO_SIZE"TRUE"
$SEC"1"
CDS_SEC"1";
"1"
$PN"1"22;
"2"
$PN"2"17;
%"Q_SHORT"
"1","(3000,-1050)","0","pure_quanta","I43";
;
PART_NUMBER"SHORT6"
MATERIAL"EMPTY"
PACK_TYPE"SM"
LOCATION"PJ62"
BOM_COST"VR_PCH"
NEEDS_NO_SIZE"TRUE"
CDS_LIB"pure_quanta"
$SEC"1"
CDS_SEC"1";
"1"
$PN"1"21;
"2"
$PN"2"6;
%"Q_CAP"
"1","(2650,-550)","0","pure_quanta","I44";
;
PART_NUMBER"CH647KMEA04"
TOLERANCE"20%"
PACK_TYPE"C0805"
VOLTAGE"4V"
VALUE"47UF"
MATERIAL"X6S"
LOCATION"PC1225"
CDS_LIB"pure_quanta"
BOM_COST"VR_PCH"
$SEC"1"
CDS_SEC"1";
"B"
$PN"2"16;
"A"
$PN"1"6;
%"Q_CAP"
"1","(3025,-550)","0","pure_quanta","I45";
;
PART_NUMBER"CH647KMEA04"
TOLERANCE"20%"
PACK_TYPE"C0805"
VOLTAGE"4V"
VALUE"47UF"
MATERIAL"X6S"
LOCATION"PC1226"
CDS_LIB"pure_quanta"
BOM_COST"VR_PCH"
$SEC"1"
CDS_SEC"1";
"B"
$PN"2"16;
"A"
$PN"1"6;
%"UNIVERSAL_GND"
"1","(3450,-875)","0","logical_power","I46";
;
HDL_POWER"GND"
CDS_LIB"logical_power";
"A"16;
%"Q_CAPP"
"1","(3450,-550)","0","pure_quanta","I47";
;
PART_NUMBER"CH733RY8807"
PACK_TYPE"SMLF"
TOLERANCE"35%"
VOLTAGE"2V"
VALUE"330UF"
MATERIAL"SPCAP"
LOCATION"PC1229"
CDS_LIB"pure_quanta"
BOM_COST"VR_PCH"
$SEC"1"
CDS_SEC"1";
"A"
$PN"1"6;
"B"
$PN"2"16;
%"Q_CAPP"
"1","(3675,-2500)","0","pure_quanta","I48";
;
PART_NUMBER"CC7560JMD16"
PACK_TYPE"THLF"
VALUE"560UF"
TOLERANCE"20%"
VOLTAGE"2.5V"
OSCON"OSCON"
LOCATION"PC1230"
MATERIAL"OSCON"
BOM_COST"VR_PCH"
CDS_LIB"pure_quanta"
$SEC"1"
CDS_SEC"1";
"A"
$PN"1"5;
"B"
$PN"2"15;
%"VCCAUX15"
"1","(3675,-2200)","0","logical_power","I49";
;
HDL_POWER"P1V05_PCH_AUX"
BOM_COST"VR_PCH"
CDS_LIB"logical_power";
"A"5;
%"UNIVERSAL_GND"
"1","(-2100,-1700)","0","logical_power","I5";
;
HDL_POWER"GND"
CDS_LIB"logical_power";
"A"8;
%"UNIVERSAL_GND"
"1","(3825,-1825)","0","logical_power","I50";
;
HDL_POWER"GND"
CDS_LIB"logical_power";
"A"17;
%"Q_RES"
"1","(975,150)","0","pure_quanta","I51";
;
PART_NUMBER"CS00002JB13"
MATERIAL"CHIP"
TOLERANCE"5%"
VALUE"0"
LOCATION"R1650"
CDS_LIB"pure_quanta"
WATTAGE"1/16W"
PACK_TYPE"0402LF"
$SEC"1"
CDS_SEC"1";
"B"
$PN"2"19;
"A"
$PN"1"20;
%"Q_RES"
"1","(975,275)","0","pure_quanta","I52";
;
PART_NUMBER"CS00002JB13"
TOLERANCE"5%"
VALUE"0"
WATTAGE"1/16W"
MATERIAL"CHIP"
PACK_TYPE"0402LF"
LOCATION"R4780"
CDS_LIB"pure_quanta"
$SEC"1"
CDS_SEC"1";
"B"
$PN"2"18;
"A"
$PN"1"20;
%"Q_INDUCTOR"
"1","(1375,-325)","0","pure_quanta","I53";
;
PART_NUMBER"CV+30Y0KZ05"
MATERIAL"IND"
VALUE"300NH/33A"
PACK_TYPE"SMLF"
LOCATION"PL150"
CDS_LIB"pure_quanta"
NEEDS_NO_SIZE"TRUE"
BOM_COST"VR_PCH"
$SEC"1"
CDS_SEC"1";
"1"
$PN"1"25;
"2"
$PN"2"6;
%"UNIVERSAL_POWER"
"1","(3825,-125)","0","logical_power","I56";
;
HDL_POWER"P1V05_PCH_AUX"
CDS_LIB"logical_power";
"A"6;
%"Q_RES"
"2","(-2100,-1450)","0","pure_quanta","I6";
;
PART_NUMBER"CS28452FB06"
PACK_TYPE"0402LF"
MATERIAL"CHIP"
WATTAGE"1/16W"
TOLERANCE"1%"
VALUE"8.45K"
LOCATION"PR1327"
CDS_LIB"pure_quanta"
$SEC"1"
CDS_SEC"1";
"A"
$PN"1"32;
"B"
$PN"2"8;
%"UNIVERSAL_GND"
"1","(-2350,-900)","0","logical_power","I7";
;
HDL_POWER"GND"
CDS_LIB"logical_power";
"A"9;
%"Q_CAP"
"1","(-2450,-575)","2","pure_quanta","I8";
;
PART_NUMBER"TMP_QCH21006JB10"
TOLERANCE"5%"
MATERIAL"EMPTY"
VALUE"1000PF"
VOLTAGE"50V"
PACK_TYPE"0402"
LOCATION"PC2286"
CDS_LIB"pure_quanta"
$SEC"1"
CDS_SEC"1";
"B"
$PN"2"9;
"A"
$PN"1"27;
%"Q_RES"
"2","(-2350,-575)","0","pure_quanta","I9";
;
PART_NUMBER"CS22002FB07"
MATERIAL"CHIP"
WATTAGE"1/16W"
VALUE"2K"
TOLERANCE"1%"
PACK_TYPE"0402LF"
LOCATION"PR1649"
CDS_LIB"pure_quanta"
$SEC"1"
CDS_SEC"1";
"A"
$PN"1"27;
"B"
$PN"2"9;
END.
